(kicad_pcb
	(version 20260206)
	(generator "pcbnew")
	(generator_version "10.0")
	(general
		(thickness 1.6)
		(legacy_teardrops no)
	)
	(paper "A4")
	(title_block
		(title "04192023_DAF0TMB3IC0_F0TG_MB_C_brd_V02_OCP.brd")
		(comment 1 "Grand Teton / footprints 444-446 of 8354")
	)
	(layers
		(0 "F.Cu" signal "TOP")
		(4 "In1.Cu" signal "GND")
		(6 "In2.Cu" signal "IN1")
		(8 "In3.Cu" signal "GND1")
		(10 "In4.Cu" signal "IN2")
		(12 "In5.Cu" signal "GND2")
		(14 "In6.Cu" signal "IN3")
		(16 "In7.Cu" signal "GND3")
		(18 "In8.Cu" signal "VCC")
		(20 "In9.Cu" signal "VCC1")
		(22 "In10.Cu" signal "GND4")
		(24 "In11.Cu" signal "IN4")
		(26 "In12.Cu" signal "GND5")
		(28 "In13.Cu" signal "IN5")
		(30 "In14.Cu" signal "GND6")
		(32 "In15.Cu" signal "IN6")
		(34 "In16.Cu" signal "GND7")
		(2 "B.Cu" signal "BOTTOM")
		(9 "F.Adhes" user "F.Adhesive")
		(11 "B.Adhes" user "B.Adhesive")
		(13 "F.Paste" user "Package Geometry/Pastemask Top")
		(15 "B.Paste" user "Package Geometry/Pastemask Bottom")
		(5 "F.SilkS" user "Ref Des/Silkscreen Top")
		(7 "B.SilkS" user "Ref Des/Silkscreen Bottom")
		(1 "F.Mask" user "Board Geometry/Soldermask Top")
		(3 "B.Mask" user "Board Geometry/Soldermask Bottom")
		(17 "Dwgs.User" user "User.Drawings")
		(19 "Cmts.User" user "User.Comments")
		(21 "Eco1.User" user "User.Eco1")
		(23 "Eco2.User" user "User.Eco2")
		(25 "Edge.Cuts" user "Board Geometry/Outline")
		(27 "Margin" user)
		(31 "F.CrtYd" user "Package Geometry/Place Bound Top")
		(29 "B.CrtYd" user "Package Geometry/Place Bound Bottom")
		(35 "F.Fab" user "Ref Des/Assembly Top")
		(33 "B.Fab" user "Ref Des/Assembly Bottom")
	)
	(footprint ""
		(layer "F.Cu")
		(at 174.625 -100.294948 90)
		(property "Reference" "R10"
			(at 0 0 90)
			(layer "F.SilkS")
			(hide yes)
			(effects
				(font
					(size 1.27 1.27)
				)
			)
		)
		(property "Value" ""
			(at 0 0 90)
			(layer "F.Fab")
			(effects
				(font
					(size 1.27 1.27)
				)
			)
		)
		(duplicate_pad_numbers_are_jumpers no)
		(fp_line
			(start 0.7874 -0.4064)
			(end 0.7874 0.4064)
			(stroke
				(width 0.1524)
				(type default)
			)
			(layer "F.SilkS")
		)
		(fp_line
			(start -0.7874 -0.4064)
			(end 0.7874 -0.4064)
			(stroke
				(width 0.1524)
				(type default)
			)
			(layer "F.SilkS")
		)
		(fp_line
			(start 0.7874 0.4064)
			(end -0.7874 0.4064)
			(stroke
				(width 0.1524)
				(type default)
			)
			(layer "F.SilkS")
		)
		(fp_line
			(start -0.7874 0.4064)
			(end -0.7874 -0.4064)
			(stroke
				(width 0.1524)
				(type default)
			)
			(layer "F.SilkS")
		)
		(fp_line
			(start -0.12065 -0.305054)
			(end -0.12065 -0.2794)
			(stroke
				(width 0.1)
				(type default)
			)
			(layer "F.Fab")
		)
		(fp_line
			(start -0.67945 -0.305054)
			(end -0.12065 -0.305054)
			(stroke
				(width 0.1)
				(type default)
			)
			(layer "F.Fab")
		)
		(fp_line
			(start 0.67945 -0.3048)
			(end 0.67945 0.3048)
			(stroke
				(width 0.1)
				(type default)
			)
			(layer "F.Fab")
		)
		(fp_line
			(start 0.12065 -0.3048)
			(end 0.67945 -0.3048)
			(stroke
				(width 0.1)
				(type default)
			)
			(layer "F.Fab")
		)
		(fp_line
			(start 0.12065 -0.2794)
			(end 0.12065 -0.3048)
			(stroke
				(width 0.1)
				(type default)
			)
			(layer "F.Fab")
		)
		(fp_line
			(start -0.12065 -0.2794)
			(end 0.12065 -0.2794)
			(stroke
				(width 0.1)
				(type default)
			)
			(layer "F.Fab")
		)
		(fp_line
			(start 0.120396 0.2794)
			(end -0.12065 0.2794)
			(stroke
				(width 0.1)
				(type default)
			)
			(layer "F.Fab")
		)
		(fp_line
			(start -0.12065 0.2794)
			(end -0.12065 0.3048)
			(stroke
				(width 0.1)
				(type default)
			)
			(layer "F.Fab")
		)
		(fp_line
			(start 0.67945 0.3048)
			(end 0.120396 0.3048)
			(stroke
				(width 0.1)
				(type default)
			)
			(layer "F.Fab")
		)
		(fp_line
			(start 0.120396 0.3048)
			(end 0.120396 0.2794)
			(stroke
				(width 0.1)
				(type default)
			)
			(layer "F.Fab")
		)
		(fp_line
			(start -0.12065 0.3048)
			(end -0.67945 0.3048)
			(stroke
				(width 0.1)
				(type default)
			)
			(layer "F.Fab")
		)
		(fp_line
			(start -0.67945 0.3048)
			(end -0.67945 -0.305054)
			(stroke
				(width 0.1)
				(type default)
			)
			(layer "F.Fab")
		)
		(pad "1" smd circle
			(at -0.40005 0 90)
			(size 0 0)
			(layers "F.Cu" "F.Mask" "F.Paste")
			(net "FM_I3C_CPU0_MUX0_OE_N")
		)
		(pad "2" smd circle
			(at 0.40005 0 90)
			(size 0 0)
			(layers "F.Cu" "F.Mask" "F.Paste")
			(net "GND")
		)
	)
	(footprint ""
		(layer "F.Cu")
		(at 65.64757 -168.928542 180)
		(property "Reference" "PU24"
			(at -0.129032 -6.648704 0)
			(unlocked yes)
			(layer "F.SilkS")
			(effects
				(font
					(size 0.7874 0.5842)
					(thickness 0.1524)
				)
				(justify left)
			)
		)
		(property "Value" ""
			(at 0 0 180)
			(layer "F.Fab")
			(effects
				(font
					(size 1.27 1.27)
				)
			)
		)
		(duplicate_pad_numbers_are_jumpers no)
		(fp_line
			(start 2.500122 2.999994)
			(end 2.2987 2.999994)
			(stroke
				(width 0.1524)
				(type default)
			)
			(layer "F.SilkS")
		)
		(fp_line
			(start 2.500122 2.339594)
			(end 2.500122 2.999994)
			(stroke
				(width 0.1524)
				(type default)
			)
			(layer "F.SilkS")
		)
		(fp_line
			(start 2.500122 -2.999994)
			(end 2.500122 -2.44348)
			(stroke
				(width 0.1524)
				(type default)
			)
			(layer "F.SilkS")
		)
		(fp_line
			(start 2.31394 -2.999994)
			(end 2.500122 -2.999994)
			(stroke
				(width 0.1524)
				(type default)
			)
			(layer "F.SilkS")
		)
		(fp_line
			(start -2.2987 2.999994)
			(end -2.500122 2.999994)
			(stroke
				(width 0.1524)
				(type default)
			)
			(layer "F.SilkS")
		)
		(fp_line
			(start -2.500122 2.999994)
			(end -2.500122 2.339594)
			(stroke
				(width 0.1524)
				(type default)
			)
			(layer "F.SilkS")
		)
		(fp_line
			(start -2.500122 0.6604)
			(end -2.500122 0.229108)
			(stroke
				(width 0.1524)
				(type default)
			)
			(layer "F.SilkS")
		)
		(fp_line
			(start -2.500122 -2.529078)
			(end -2.500122 -2.999994)
			(stroke
				(width 0.1524)
				(type default)
			)
			(layer "F.SilkS")
		)
		(fp_line
			(start -2.500122 -2.999994)
			(end -2.24409 -2.999994)
			(stroke
				(width 0.1524)
				(type default)
			)
			(layer "F.SilkS")
		)
		(fp_poly
			(pts
				(xy -2.695956 -2.436622) (xy -3.492754 -2.702306) (xy -2.96164 -3.233166)
			)
			(stroke
				(width 0)
				(type default)
			)
			(fill yes)
			(layer "F.SilkS")
		)
		(fp_line
			(start 2.500122 2.999994)
			(end -2.500122 2.999994)
			(stroke
				(width 0.1)
				(type default)
			)
			(layer "F.Fab")
		)
		(fp_line
			(start 2.500122 -2.999994)
			(end 2.500122 2.999994)
			(stroke
				(width 0.1)
				(type default)
			)
			(layer "F.Fab")
		)
		(fp_line
			(start -2.500122 2.999994)
			(end -2.500122 -2.999994)
			(stroke
				(width 0.1)
				(type default)
			)
			(layer "F.Fab")
		)
		(fp_line
			(start -2.500122 -2.999994)
			(end 2.500122 -2.999994)
			(stroke
				(width 0.1)
				(type default)
			)
			(layer "F.Fab")
		)
		(fp_poly
			(pts
				(xy -4.218432 -2.783078) (xy -4.218432 -1.767078) (xy -3.202432 -2.275078)
			)
			(stroke
				(width 0)
				(type default)
			)
			(fill yes)
			(layer "F.Fab")
		)
		(pad "1" smd rect
			(at -2.400046 -2.275078 270)
			(size 0.2286 0.6096)
			(layers "F.Cu" "F.Mask" "F.Paste")
			(net "PVDDCR_CPU0_P1_VOS6")
		)
		(pad "2" smd rect
			(at -2.400046 -1.82499 270)
			(size 0.2286 0.6096)
			(layers "F.Cu" "F.Mask" "F.Paste")
			(net "GND")
		)
		(pad "3" smd rect
			(at -2.400046 -1.374902 270)
			(size 0.2286 0.6096)
			(layers "F.Cu" "F.Mask" "F.Paste")
			(net "PVDDCR_CPU0_P1_VCC6")
		)
		(pad "4" smd rect
			(at -2.400046 -0.925068 270)
			(size 0.2286 0.6096)
			(layers "F.Cu" "F.Mask" "F.Paste")
			(net "PVDDCR_CPU0_P1_PVCC")
		)
		(pad "5" smd rect
			(at -2.400046 -0.47498 270)
			(size 0.2286 0.6096)
			(layers "F.Cu" "F.Mask" "F.Paste")
			(net "GND")
		)
		(pad "6" smd rect
			(at -2.400046 -0.024892 270)
			(size 0.2286 0.6096)
			(layers "F.Cu" "F.Mask" "F.Paste")
			(net "NC_PVDDCR_CPU0_P1_GL1_6")
		)
		(pad "7_9-20_24" smd circle
			(at 0 1.150112 270)
			(size 0 0)
			(layers "F.Cu" "F.Mask" "F.Paste")
			(net "GND")
		)
		(pad "10_19" smd rect
			(at 0 2.899918 270)
			(size 0.6096 4.318)
			(layers "F.Cu" "F.Mask" "F.Paste")
			(net "SW_PVDDCR_CPU0_P1_SW6")
		)
		(pad "25_29" smd rect
			(at 1.549908 -1.279906 90)
			(size 2.0574 2.3114)
			(layers "F.Cu" "F.Mask" "F.Paste")
			(net "SW_P12V_AUX_PVDDCR_CPU0_P1_FLT")
		)
		(pad "30" smd rect
			(at 2.05994 -2.899918 180)
			(size 0.2286 0.6096)
			(layers "F.Cu" "F.Mask" "F.Paste")
			(net "SW_P12V_AUX_PVDDCR_CPU0_P1_FLT")
		)
		(pad "31" smd rect
			(at 1.610106 -2.899918 180)
			(size 0.2286 0.6096)
			(layers "F.Cu" "F.Mask" "F.Paste")
			(net "NC_PVDDCR_CPU0_P1_DNC6")
		)
		(pad "32" smd rect
			(at 1.160018 -2.899918 180)
			(size 0.2286 0.6096)
			(layers "F.Cu" "F.Mask" "F.Paste")
			(net "SW_PVDDCR_CPU0_P1_PH6")
		)
		(pad "33" smd rect
			(at 0.70993 -2.899918 180)
			(size 0.2286 0.6096)
			(layers "F.Cu" "F.Mask" "F.Paste")
			(net "SW_PVDDCR_CPU0_P1_BOOT6")
		)
		(pad "34" smd rect
			(at 0.260096 -2.899918 180)
			(size 0.2286 0.6096)
			(layers "F.Cu" "F.Mask" "F.Paste")
			(net "PVDDCR_CPU0_P1_PWM6")
		)
		(pad "35" smd rect
			(at -0.189992 -2.899918 180)
			(size 0.2286 0.6096)
			(layers "F.Cu" "F.Mask" "F.Paste")
			(net "PVDDCR_CPU0_P1_VCC6")
		)
		(pad "36" smd rect
			(at -0.64008 -2.899918 180)
			(size 0.2286 0.6096)
			(layers "F.Cu" "F.Mask" "F.Paste")
			(net "PVDDCR_CPU0_P1_TEMP0")
		)
		(pad "37" smd rect
			(at -1.089914 -2.899918 180)
			(size 0.2286 0.6096)
			(layers "F.Cu" "F.Mask" "F.Paste")
			(net "PVDDCR_CPU0_P1_LSET6")
		)
		(pad "38" smd rect
			(at -1.540002 -2.899918 180)
			(size 0.2286 0.6096)
			(layers "F.Cu" "F.Mask" "F.Paste")
			(net "PVDDCR_CPU0_P1_IMON6")
		)
		(pad "39" smd rect
			(at -1.99009 -2.899918 180)
			(size 0.2286 0.6096)
			(layers "F.Cu" "F.Mask" "F.Paste")
			(net "PVDDCR_CPU0_P1_VCCS")
		)
		(pad "40" smd rect
			(at -0.87503 -1.27508 180)
			(size 1.7526 1.9558)
			(layers "F.Cu" "F.Mask" "F.Paste")
			(net "GND")
		)
		(pad "41" smd rect
			(at -1.525016 0.249936 90)
			(size 0.3048 0.4572)
			(layers "F.Cu" "F.Mask" "F.Paste")
			(net "NC_PVDDCR_CPU0_P1_GL2_6")
		)
		(zone
			(layer "F.Cu")
			(hatch none 0.5)
			(connect_pads
				(clearance 0)
			)
			(min_thickness 0.25)
			(keepout
				(tracks not_allowed)
				(vias allowed)
				(pads allowed)
				(copperpour not_allowed)
				(footprints allowed)
			)
			(placement
				(enabled no)
				(sheetname "")
			)
			(fill
				(thermal_gap 0.5)
				(thermal_bridge_width 0.5)
				(island_removal_mode 0)
			)
			(polygon
				(pts
					(xy 68.147692 -171.47286) (xy 68.147692 -171.179236) (xy 63.147448 -171.179236) (xy 63.147448 -171.47286)
					(xy 63.43777 -171.47286) (xy 67.85737 -171.47286)
				)
			)
		)
		(zone
			(layer "F.Cu")
			(hatch none 0.5)
			(connect_pads
				(clearance 0)
			)
			(min_thickness 0.25)
			(keepout
				(tracks not_allowed)
				(vias allowed)
				(pads allowed)
				(copperpour not_allowed)
				(footprints allowed)
			)
			(placement
				(enabled no)
				(sheetname "")
			)
			(fill
				(thermal_gap 0.5)
				(thermal_bridge_width 0.5)
				(island_removal_mode 0)
			)
			(polygon
				(pts
					(xy 65.5955 -168.682162) (xy 65.5955 -166.624762) (xy 67.4497 -166.624762) (xy 67.4497 -166.865808)
					(xy 67.692016 -166.865808) (xy 67.692016 -166.384224) (xy 63.80353 -166.384224) (xy 63.80353 -166.569136)
					(xy 65.304162 -166.569136) (xy 65.304162 -168.728136) (xy 63.147448 -168.728136) (xy 63.147448 -168.977818)
					(xy 65.299844 -168.977818)
				)
			)
		)
	)
	(footprint ""
		(layer "F.Cu")
		(at 152.849326 -36.99256 180)
		(property "Reference" "R3229"
			(at 0 0 180)
			(layer "F.SilkS")
			(hide yes)
			(effects
				(font
					(size 1.27 1.27)
				)
			)
		)
		(property "Value" ""
			(at 0 0 180)
			(layer "F.Fab")
			(effects
				(font
					(size 1.27 1.27)
				)
			)
		)
		(duplicate_pad_numbers_are_jumpers no)
		(fp_line
			(start 0.7874 0.4064)
			(end -0.7874 0.4064)
			(stroke
				(width 0.1524)
				(type default)
			)
			(layer "F.SilkS")
		)
		(fp_line
			(start 0.7874 -0.4064)
			(end 0.7874 0.4064)
			(stroke
				(width 0.1524)
				(type default)
			)
			(layer "F.SilkS")
		)
		(fp_line
			(start -0.7874 0.4064)
			(end -0.7874 -0.4064)
			(stroke
				(width 0.1524)
				(type default)
			)
			(layer "F.SilkS")
		)
		(fp_line
			(start -0.7874 -0.4064)
			(end 0.7874 -0.4064)
			(stroke
				(width 0.1524)
				(type default)
			)
			(layer "F.SilkS")
		)
		(fp_line
			(start 0.67945 0.3048)
			(end 0.120396 0.3048)
			(stroke
				(width 0.1)
				(type default)
			)
			(layer "F.Fab")
		)
		(fp_line
			(start 0.67945 -0.3048)
			(end 0.67945 0.3048)
			(stroke
				(width 0.1)
				(type default)
			)
			(layer "F.Fab")
		)
		(fp_line
			(start 0.12065 -0.2794)
			(end 0.12065 -0.3048)
			(stroke
				(width 0.1)
				(type default)
			)
			(layer "F.Fab")
		)
		(fp_line
			(start 0.12065 -0.3048)
			(end 0.67945 -0.3048)
			(stroke
				(width 0.1)
				(type default)
			)
			(layer "F.Fab")
		)
		(fp_line
			(start 0.120396 0.3048)
			(end 0.120396 0.2794)
			(stroke
				(width 0.1)
				(type default)
			)
			(layer "F.Fab")
		)
		(fp_line
			(start 0.120396 0.2794)
			(end -0.12065 0.2794)
			(stroke
				(width 0.1)
				(type default)
			)
			(layer "F.Fab")
		)
		(fp_line
			(start -0.12065 0.3048)
			(end -0.67945 0.3048)
			(stroke
				(width 0.1)
				(type default)
			)
			(layer "F.Fab")
		)
		(fp_line
			(start -0.12065 0.2794)
			(end -0.12065 0.3048)
			(stroke
				(width 0.1)
				(type default)
			)
			(layer "F.Fab")
		)
		(fp_line
			(start -0.12065 -0.2794)
			(end 0.12065 -0.2794)
			(stroke
				(width 0.1)
				(type default)
			)
			(layer "F.Fab")
		)
		(fp_line
			(start -0.12065 -0.305054)
			(end -0.12065 -0.2794)
			(stroke
				(width 0.1)
				(type default)
			)
			(layer "F.Fab")
		)
		(fp_line
			(start -0.67945 0.3048)
			(end -0.67945 -0.305054)
			(stroke
				(width 0.1)
				(type default)
			)
			(layer "F.Fab")
		)
		(fp_line
			(start -0.67945 -0.305054)
			(end -0.12065 -0.305054)
			(stroke
				(width 0.1)
				(type default)
			)
			(layer "F.Fab")
		)
		(pad "1" smd circle
			(at -0.40005 0 180)
			(size 0 0)
			(layers "F.Cu" "F.Mask" "F.Paste")
			(net "SMB_OCP_V3_2_3V3AUX_BUF_R_SDA")
		)
		(pad "2" smd circle
			(at 0.40005 0 180)
			(size 0 0)
			(layers "F.Cu" "F.Mask" "F.Paste")
			(net "SMB_OCP_V3_2_3V3AUX_BUF_SDA")
		)
	)
)
